# SCM (Grand Teton) — schematic netlist excerpt (pin names and nets, part order shuffled) for the footprints in the layout excerpt that follows; sources: Cadence DE-HDL packaged netlist, KiCad conversion of 12092022_DA0F0TMDCD0_F0T_Management_Board_D_brd_V3_OCP.brd

R798  Q_RES  2K 1% CHIP  pkg 0402LF  page 15 : A = PGPPA_BMC_AUX_SENSOR ; B = GND
R229  Q_RES  4.7K 1% EMPTY  pkg 0402LF  page 32 : A = GND ; B = JTAG_MB_TRST_N

(kicad_pcb
	(version 20260206)
	(generator "pcbnew")
	(generator_version "10.0")
	(general
		(thickness 1.6)
		(legacy_teardrops no)
	)
	(paper "A4")
	(title_block
		(title "12092022_DA0F0TMDCD0_F0T_Management_Board_D_brd_V3_OCP.brd")
		(comment 1 "Grand Teton / footprints 779-780 of 1440")
	)
	(layers
		(0 "F.Cu" signal "TOP")
		(4 "In1.Cu" signal "GND")
		(6 "In2.Cu" signal "IN1")
		(8 "In3.Cu" signal "GND1")
		(10 "In4.Cu" signal "IN2")
		(12 "In5.Cu" signal "VCC")
		(14 "In6.Cu" signal "VCC1")
		(16 "In7.Cu" signal "IN3")
		(18 "In8.Cu" signal "GND2")
		(20 "In9.Cu" signal "IN4")
		(22 "In10.Cu" signal "GND3")
		(2 "B.Cu" signal "BOTTOM")
		(9 "F.Adhes" user "F.Adhesive")
		(11 "B.Adhes" user "B.Adhesive")
		(13 "F.Paste" user "Package Geometry/Pastemask Top")
		(15 "B.Paste" user "Package Geometry/Pastemask Bottom")
		(5 "F.SilkS" user "Ref Des/Silkscreen Top")
		(7 "B.SilkS" user "Ref Des/Silkscreen Bottom")
		(1 "F.Mask" user "Board Geometry/Soldermask Top")
		(3 "B.Mask" user "Board Geometry/Soldermask Bottom")
		(17 "Dwgs.User" user "User.Drawings")
		(19 "Cmts.User" user "User.Comments")
		(21 "Eco1.User" user "User.Eco1")
		(23 "Eco2.User" user "User.Eco2")
		(25 "Edge.Cuts" user "Board Geometry/Outline")
		(27 "Margin" user)
		(31 "F.CrtYd" user "Package Geometry/Place Bound Top")
		(29 "B.CrtYd" user "Package Geometry/Place Bound Bottom")
		(35 "F.Fab" user "Ref Des/Assembly Top")
		(33 "B.Fab" user "Ref Des/Assembly Bottom")
	)
	(footprint ""
		(layer "B.Cu")
		(at 51.816 -30.861 -90)
		(property "Reference" "R229"
			(at 0 0 90)
			(layer "B.SilkS")
			(hide yes)
			(effects
				(font
					(size 1.27 1.27)
				)
				(justify mirror)
			)
		)
		(property "Value" ""
			(at 0 0 90)
			(layer "B.Fab")
			(effects
				(font
					(size 1.27 1.27)
				)
				(justify mirror)
			)
		)
		(duplicate_pad_numbers_are_jumpers no)
		(fp_line
			(start -0.7874 0.4064)
			(end 0.7874 0.4064)
			(stroke
				(width 0.1524)
				(type default)
			)
			(layer "B.SilkS")
		)
		(fp_line
			(start 0.7874 0.4064)
			(end 0.7874 -0.4064)
			(stroke
				(width 0.1524)
				(type default)
			)
			(layer "B.SilkS")
		)
		(fp_line
			(start -0.7874 -0.4064)
			(end -0.7874 0.4064)
			(stroke
				(width 0.1524)
				(type default)
			)
			(layer "B.SilkS")
		)
		(fp_line
			(start 0.7874 -0.4064)
			(end -0.7874 -0.4064)
			(stroke
				(width 0.1524)
				(type default)
			)
			(layer "B.SilkS")
		)
		(fp_line
			(start -0.67945 0.3048)
			(end -0.120396 0.3048)
			(stroke
				(width 0.1)
				(type default)
			)
			(layer "B.Fab")
		)
		(fp_line
			(start -0.120396 0.3048)
			(end -0.120396 0.2794)
			(stroke
				(width 0.1)
				(type default)
			)
			(layer "B.Fab")
		)
		(fp_line
			(start 0.12065 0.3048)
			(end 0.67945 0.3048)
			(stroke
				(width 0.1)
				(type default)
			)
			(layer "B.Fab")
		)
		(fp_line
			(start 0.67945 0.3048)
			(end 0.67945 -0.305054)
			(stroke
				(width 0.1)
				(type default)
			)
			(layer "B.Fab")
		)
		(fp_line
			(start -0.120396 0.2794)
			(end 0.12065 0.2794)
			(stroke
				(width 0.1)
				(type default)
			)
			(layer "B.Fab")
		)
		(fp_line
			(start 0.12065 0.2794)
			(end 0.12065 0.3048)
			(stroke
				(width 0.1)
				(type default)
			)
			(layer "B.Fab")
		)
		(fp_line
			(start -0.12065 -0.2794)
			(end -0.12065 -0.3048)
			(stroke
				(width 0.1)
				(type default)
			)
			(layer "B.Fab")
		)
		(fp_line
			(start 0.12065 -0.2794)
			(end -0.12065 -0.2794)
			(stroke
				(width 0.1)
				(type default)
			)
			(layer "B.Fab")
		)
		(fp_line
			(start -0.67945 -0.3048)
			(end -0.67945 0.3048)
			(stroke
				(width 0.1)
				(type default)
			)
			(layer "B.Fab")
		)
		(fp_line
			(start -0.12065 -0.3048)
			(end -0.67945 -0.3048)
			(stroke
				(width 0.1)
				(type default)
			)
			(layer "B.Fab")
		)
		(fp_line
			(start 0.12065 -0.305054)
			(end 0.12065 -0.2794)
			(stroke
				(width 0.1)
				(type default)
			)
			(layer "B.Fab")
		)
		(fp_line
			(start 0.67945 -0.305054)
			(end 0.12065 -0.305054)
			(stroke
				(width 0.1)
				(type default)
			)
			(layer "B.Fab")
		)
		(pad "1" smd circle
			(at 0.40005 0 90)
			(size 0 0)
			(layers "B.Cu" "B.Mask" "B.Paste")
			(net "GND")
		)
		(pad "2" smd circle
			(at -0.40005 0 90)
			(size 0 0)
			(layers "B.Cu" "B.Mask" "B.Paste")
			(net "JTAG_MB_TRST_N")
		)
	)
	(footprint ""
		(layer "B.Cu")
		(at 58.890662 -70.063614)
		(property "Reference" "R798"
			(at 0 0 0)
			(layer "B.SilkS")
			(hide yes)
			(effects
				(font
					(size 1.27 1.27)
				)
				(justify mirror)
			)
		)
		(property "Value" ""
			(at 0 0 0)
			(layer "B.Fab")
			(effects
				(font
					(size 1.27 1.27)
				)
				(justify mirror)
			)
		)
		(duplicate_pad_numbers_are_jumpers no)
		(fp_line
			(start -0.7874 -0.4064)
			(end -0.7874 0.4064)
			(stroke
				(width 0.1524)
				(type default)
			)
			(layer "B.SilkS")
		)
		(fp_line
			(start -0.7874 0.4064)
			(end 0.7874 0.4064)
			(stroke
				(width 0.1524)
				(type default)
			)
			(layer "B.SilkS")
		)
		(fp_line
			(start 0.7874 -0.4064)
			(end -0.7874 -0.4064)
			(stroke
				(width 0.1524)
				(type default)
			)
			(layer "B.SilkS")
		)
		(fp_line
			(start 0.7874 0.4064)
			(end 0.7874 -0.4064)
			(stroke
				(width 0.1524)
				(type default)
			)
			(layer "B.SilkS")
		)
		(fp_line
			(start -0.67945 -0.3048)
			(end -0.67945 0.3048)
			(stroke
				(width 0.1)
				(type default)
			)
			(layer "B.Fab")
		)
		(fp_line
			(start -0.67945 0.3048)
			(end -0.120396 0.3048)
			(stroke
				(width 0.1)
				(type default)
			)
			(layer "B.Fab")
		)
		(fp_line
			(start -0.12065 -0.3048)
			(end -0.67945 -0.3048)
			(stroke
				(width 0.1)
				(type default)
			)
			(layer "B.Fab")
		)
		(fp_line
			(start -0.12065 -0.2794)
			(end -0.12065 -0.3048)
			(stroke
				(width 0.1)
				(type default)
			)
			(layer "B.Fab")
		)
		(fp_line
			(start -0.120396 0.2794)
			(end 0.12065 0.2794)
			(stroke
				(width 0.1)
				(type default)
			)
			(layer "B.Fab")
		)
		(fp_line
			(start -0.120396 0.3048)
			(end -0.120396 0.2794)
			(stroke
				(width 0.1)
				(type default)
			)
			(layer "B.Fab")
		)
		(fp_line
			(start 0.12065 -0.305054)
			(end 0.12065 -0.2794)
			(stroke
				(width 0.1)
				(type default)
			)
			(layer "B.Fab")
		)
		(fp_line
			(start 0.12065 -0.2794)
			(end -0.12065 -0.2794)
			(stroke
				(width 0.1)
				(type default)
			)
			(layer "B.Fab")
		)
		(fp_line
			(start 0.12065 0.2794)
			(end 0.12065 0.3048)
			(stroke
				(width 0.1)
				(type default)
			)
			(layer "B.Fab")
		)
		(fp_line
			(start 0.12065 0.3048)
			(end 0.67945 0.3048)
			(stroke
				(width 0.1)
				(type default)
			)
			(layer "B.Fab")
		)
		(fp_line
			(start 0.67945 -0.305054)
			(end 0.12065 -0.305054)
			(stroke
				(width 0.1)
				(type default)
			)
			(layer "B.Fab")
		)
		(fp_line
			(start 0.67945 0.3048)
			(end 0.67945 -0.305054)
			(stroke
				(width 0.1)
				(type default)
			)
			(layer "B.Fab")
		)
		(pad "1" smd circle
			(at 0.40005 0 180)
			(size 0 0)
			(layers "B.Cu" "B.Mask" "B.Paste")
			(net "PGPPA_BMC_AUX_SENSOR")
		)
		(pad "2" smd circle
			(at -0.40005 0 180)
			(size 0 0)
			(layers "B.Cu" "B.Mask" "B.Paste")
			(net "GND")
		)
	)
)
